(kicad_pcb
	(version 20260206)
	(generator "pcbnew")
	(generator_version "10.0")
	(general
		(thickness 1.6)
		(legacy_teardrops no)
	)
	(paper "A4")
	(title_block
		(title "03242023_DA0F0TMBIJ0_F0T_Motherboard_J_brd_V01_OCP.brd")
		(comment 1 "Grand Teton / footprints 1271-1277 of 6105")
	)
	(layers
		(0 "F.Cu" signal "TOP")
		(4 "In1.Cu" signal "GND")
		(6 "In2.Cu" signal "IN1")
		(8 "In3.Cu" signal "GND1")
		(10 "In4.Cu" signal "IN2")
		(12 "In5.Cu" signal "GND2")
		(14 "In6.Cu" signal "IN3")
		(16 "In7.Cu" signal "GND3")
		(18 "In8.Cu" signal "VCC")
		(20 "In9.Cu" signal "VCC1")
		(22 "In10.Cu" signal "GND4")
		(24 "In11.Cu" signal "IN4")
		(26 "In12.Cu" signal "GND5")
		(28 "In13.Cu" signal "IN5")
		(30 "In14.Cu" signal "GND6")
		(32 "In15.Cu" signal "IN6")
		(34 "In16.Cu" signal "GND7")
		(2 "B.Cu" signal "BOTTOM")
		(9 "F.Adhes" user "F.Adhesive")
		(11 "B.Adhes" user "B.Adhesive")
		(13 "F.Paste" user "Package Geometry/Pastemask Top")
		(15 "B.Paste" user "Package Geometry/Pastemask Bottom")
		(5 "F.SilkS" user "Ref Des/Silkscreen Top")
		(7 "B.SilkS" user "Ref Des/Silkscreen Bottom")
		(1 "F.Mask" user "Board Geometry/Soldermask Top")
		(3 "B.Mask" user "Board Geometry/Soldermask Bottom")
		(17 "Dwgs.User" user "User.Drawings")
		(19 "Cmts.User" user "User.Comments")
		(21 "Eco1.User" user "User.Eco1")
		(23 "Eco2.User" user "User.Eco2")
		(25 "Edge.Cuts" user "Board Geometry/Outline")
		(27 "Margin" user)
		(31 "F.CrtYd" user "Package Geometry/Place Bound Top")
		(29 "B.CrtYd" user "Package Geometry/Place Bound Bottom")
		(35 "F.Fab" user "Ref Des/Assembly Top")
		(33 "B.Fab" user "Ref Des/Assembly Bottom")
	)
	(footprint ""
		(layer "F.Cu")
		(at 112.27308 -397.874998 -90)
		(property "Reference" "R3035"
			(at 0 0 270)
			(layer "F.SilkS")
			(hide yes)
			(effects
				(font
					(size 1.27 1.27)
				)
			)
		)
		(property "Value" ""
			(at 0 0 270)
			(layer "F.Fab")
			(effects
				(font
					(size 1.27 1.27)
				)
			)
		)
		(duplicate_pad_numbers_are_jumpers no)
		(fp_line
			(start -0.7874 0.4064)
			(end -0.7874 -0.4064)
			(stroke
				(width 0.1524)
				(type default)
			)
			(layer "F.SilkS")
		)
		(fp_line
			(start 0.7874 0.4064)
			(end -0.7874 0.4064)
			(stroke
				(width 0.1524)
				(type default)
			)
			(layer "F.SilkS")
		)
		(fp_line
			(start -0.7874 -0.4064)
			(end 0.7874 -0.4064)
			(stroke
				(width 0.1524)
				(type default)
			)
			(layer "F.SilkS")
		)
		(fp_line
			(start 0.7874 -0.4064)
			(end 0.7874 0.4064)
			(stroke
				(width 0.1524)
				(type default)
			)
			(layer "F.SilkS")
		)
		(fp_line
			(start -0.67945 0.3048)
			(end -0.67945 -0.305054)
			(stroke
				(width 0.1)
				(type default)
			)
			(layer "F.Fab")
		)
		(fp_line
			(start -0.12065 0.3048)
			(end -0.67945 0.3048)
			(stroke
				(width 0.1)
				(type default)
			)
			(layer "F.Fab")
		)
		(fp_line
			(start 0.120396 0.3048)
			(end 0.120396 0.2794)
			(stroke
				(width 0.1)
				(type default)
			)
			(layer "F.Fab")
		)
		(fp_line
			(start 0.67945 0.3048)
			(end 0.120396 0.3048)
			(stroke
				(width 0.1)
				(type default)
			)
			(layer "F.Fab")
		)
		(fp_line
			(start -0.12065 0.2794)
			(end -0.12065 0.3048)
			(stroke
				(width 0.1)
				(type default)
			)
			(layer "F.Fab")
		)
		(fp_line
			(start 0.120396 0.2794)
			(end -0.12065 0.2794)
			(stroke
				(width 0.1)
				(type default)
			)
			(layer "F.Fab")
		)
		(fp_line
			(start -0.12065 -0.2794)
			(end 0.12065 -0.2794)
			(stroke
				(width 0.1)
				(type default)
			)
			(layer "F.Fab")
		)
		(fp_line
			(start 0.12065 -0.2794)
			(end 0.12065 -0.3048)
			(stroke
				(width 0.1)
				(type default)
			)
			(layer "F.Fab")
		)
		(fp_line
			(start 0.12065 -0.3048)
			(end 0.67945 -0.3048)
			(stroke
				(width 0.1)
				(type default)
			)
			(layer "F.Fab")
		)
		(fp_line
			(start 0.67945 -0.3048)
			(end 0.67945 0.3048)
			(stroke
				(width 0.1)
				(type default)
			)
			(layer "F.Fab")
		)
		(fp_line
			(start -0.67945 -0.305054)
			(end -0.12065 -0.305054)
			(stroke
				(width 0.1)
				(type default)
			)
			(layer "F.Fab")
		)
		(fp_line
			(start -0.12065 -0.305054)
			(end -0.12065 -0.2794)
			(stroke
				(width 0.1)
				(type default)
			)
			(layer "F.Fab")
		)
		(pad "1" smd circle
			(at -0.40005 0 270)
			(size 0 0)
			(layers "F.Cu" "F.Mask" "F.Paste")
			(net "P3V3_AUX")
		)
		(pad "2" smd circle
			(at 0.40005 0 270)
			(size 0 0)
			(layers "F.Cu" "F.Mask" "F.Paste")
			(net "FM_SMB_2_ALERT_GPU_ISO_N")
		)
	)
	(footprint ""
		(layer "F.Cu")
		(at 376.72137 -408.517344 -90)
		(property "Reference" "C873"
			(at 0 0 270)
			(layer "F.SilkS")
			(hide yes)
			(effects
				(font
					(size 1.27 1.27)
				)
			)
		)
		(property "Value" ""
			(at 0 0 270)
			(layer "F.Fab")
			(effects
				(font
					(size 1.27 1.27)
				)
			)
		)
		(duplicate_pad_numbers_are_jumpers no)
		(fp_line
			(start -0.299974 0.150114)
			(end -0.299974 -0.150114)
			(stroke
				(width 0.1)
				(type default)
			)
			(layer "F.Fab")
		)
		(fp_line
			(start 0.299974 0.150114)
			(end -0.299974 0.150114)
			(stroke
				(width 0.1)
				(type default)
			)
			(layer "F.Fab")
		)
		(fp_line
			(start -0.299974 -0.150114)
			(end 0.299974 -0.150114)
			(stroke
				(width 0.1)
				(type default)
			)
			(layer "F.Fab")
		)
		(fp_line
			(start 0.299974 -0.150114)
			(end 0.299974 0.150114)
			(stroke
				(width 0.1)
				(type default)
			)
			(layer "F.Fab")
		)
		(pad "1" smd rect
			(at -0.2667 0 270)
			(size 0.3048 0.381)
			(layers "F.Cu" "F.Mask" "F.Paste")
			(net "P5E_CPU0_PE3_TX_C_DP<14>")
		)
		(pad "2" smd rect
			(at 0.2667 0 270)
			(size 0.3048 0.381)
			(layers "F.Cu" "F.Mask" "F.Paste")
			(net "P5E_CPU0_PE3_TX_DP<14>")
		)
	)
	(footprint ""
		(layer "F.Cu")
		(at 68.085716 -112.70869)
		(property "Reference" "R3704"
			(at 0 0 0)
			(layer "F.SilkS")
			(hide yes)
			(effects
				(font
					(size 1.27 1.27)
				)
			)
		)
		(property "Value" ""
			(at 0 0 0)
			(layer "F.Fab")
			(effects
				(font
					(size 1.27 1.27)
				)
			)
		)
		(duplicate_pad_numbers_are_jumpers no)
		(fp_line
			(start -0.7874 -0.4064)
			(end 0.7874 -0.4064)
			(stroke
				(width 0.1524)
				(type default)
			)
			(layer "F.SilkS")
		)
		(fp_line
			(start -0.7874 0.4064)
			(end -0.7874 -0.4064)
			(stroke
				(width 0.1524)
				(type default)
			)
			(layer "F.SilkS")
		)
		(fp_line
			(start 0.7874 -0.4064)
			(end 0.7874 0.4064)
			(stroke
				(width 0.1524)
				(type default)
			)
			(layer "F.SilkS")
		)
		(fp_line
			(start 0.7874 0.4064)
			(end -0.7874 0.4064)
			(stroke
				(width 0.1524)
				(type default)
			)
			(layer "F.SilkS")
		)
		(fp_line
			(start -0.67945 -0.305054)
			(end -0.12065 -0.305054)
			(stroke
				(width 0.1)
				(type default)
			)
			(layer "F.Fab")
		)
		(fp_line
			(start -0.67945 0.3048)
			(end -0.67945 -0.305054)
			(stroke
				(width 0.1)
				(type default)
			)
			(layer "F.Fab")
		)
		(fp_line
			(start -0.12065 -0.305054)
			(end -0.12065 -0.2794)
			(stroke
				(width 0.1)
				(type default)
			)
			(layer "F.Fab")
		)
		(fp_line
			(start -0.12065 -0.2794)
			(end 0.12065 -0.2794)
			(stroke
				(width 0.1)
				(type default)
			)
			(layer "F.Fab")
		)
		(fp_line
			(start -0.12065 0.2794)
			(end -0.12065 0.3048)
			(stroke
				(width 0.1)
				(type default)
			)
			(layer "F.Fab")
		)
		(fp_line
			(start -0.12065 0.3048)
			(end -0.67945 0.3048)
			(stroke
				(width 0.1)
				(type default)
			)
			(layer "F.Fab")
		)
		(fp_line
			(start 0.120396 0.2794)
			(end -0.12065 0.2794)
			(stroke
				(width 0.1)
				(type default)
			)
			(layer "F.Fab")
		)
		(fp_line
			(start 0.120396 0.3048)
			(end 0.120396 0.2794)
			(stroke
				(width 0.1)
				(type default)
			)
			(layer "F.Fab")
		)
		(fp_line
			(start 0.12065 -0.3048)
			(end 0.67945 -0.3048)
			(stroke
				(width 0.1)
				(type default)
			)
			(layer "F.Fab")
		)
		(fp_line
			(start 0.12065 -0.2794)
			(end 0.12065 -0.3048)
			(stroke
				(width 0.1)
				(type default)
			)
			(layer "F.Fab")
		)
		(fp_line
			(start 0.67945 -0.3048)
			(end 0.67945 0.3048)
			(stroke
				(width 0.1)
				(type default)
			)
			(layer "F.Fab")
		)
		(fp_line
			(start 0.67945 0.3048)
			(end 0.120396 0.3048)
			(stroke
				(width 0.1)
				(type default)
			)
			(layer "F.Fab")
		)
		(pad "1" smd circle
			(at -0.40005 0)
			(size 0 0)
			(layers "F.Cu" "F.Mask" "F.Paste")
			(net "PCA9548_PCIE0_ADDR2")
		)
		(pad "2" smd circle
			(at 0.40005 0)
			(size 0 0)
			(layers "F.Cu" "F.Mask" "F.Paste")
			(net "GND")
		)
	)
	(footprint ""
		(layer "F.Cu")
		(at 197.41388 -111.724948 -90)
		(property "Reference" "C1320"
			(at 0 0 270)
			(layer "F.SilkS")
			(hide yes)
			(effects
				(font
					(size 1.27 1.27)
				)
			)
		)
		(property "Value" ""
			(at 0 0 270)
			(layer "F.Fab")
			(effects
				(font
					(size 1.27 1.27)
				)
			)
		)
		(duplicate_pad_numbers_are_jumpers no)
		(fp_line
			(start -0.7874 0.4064)
			(end -0.7874 -0.4064)
			(stroke
				(width 0.1524)
				(type default)
			)
			(layer "F.SilkS")
		)
		(fp_line
			(start 0.7874 0.4064)
			(end -0.7874 0.4064)
			(stroke
				(width 0.1524)
				(type default)
			)
			(layer "F.SilkS")
		)
		(fp_line
			(start -0.7874 -0.4064)
			(end 0.7874 -0.4064)
			(stroke
				(width 0.1524)
				(type default)
			)
			(layer "F.SilkS")
		)
		(fp_line
			(start 0.7874 -0.4064)
			(end 0.7874 0.4064)
			(stroke
				(width 0.1524)
				(type default)
			)
			(layer "F.SilkS")
		)
		(fp_line
			(start -0.67945 0.3048)
			(end -0.67945 -0.305054)
			(stroke
				(width 0.1)
				(type default)
			)
			(layer "F.Fab")
		)
		(fp_line
			(start -0.12065 0.3048)
			(end -0.67945 0.3048)
			(stroke
				(width 0.1)
				(type default)
			)
			(layer "F.Fab")
		)
		(fp_line
			(start 0.120396 0.3048)
			(end 0.120396 0.2794)
			(stroke
				(width 0.1)
				(type default)
			)
			(layer "F.Fab")
		)
		(fp_line
			(start 0.67945 0.3048)
			(end 0.120396 0.3048)
			(stroke
				(width 0.1)
				(type default)
			)
			(layer "F.Fab")
		)
		(fp_line
			(start -0.12065 0.2794)
			(end -0.12065 0.3048)
			(stroke
				(width 0.1)
				(type default)
			)
			(layer "F.Fab")
		)
		(fp_line
			(start 0.120396 0.2794)
			(end -0.12065 0.2794)
			(stroke
				(width 0.1)
				(type default)
			)
			(layer "F.Fab")
		)
		(fp_line
			(start -0.12065 -0.2794)
			(end 0.12065 -0.2794)
			(stroke
				(width 0.1)
				(type default)
			)
			(layer "F.Fab")
		)
		(fp_line
			(start 0.12065 -0.2794)
			(end 0.12065 -0.3048)
			(stroke
				(width 0.1)
				(type default)
			)
			(layer "F.Fab")
		)
		(fp_line
			(start 0.12065 -0.3048)
			(end 0.67945 -0.3048)
			(stroke
				(width 0.1)
				(type default)
			)
			(layer "F.Fab")
		)
		(fp_line
			(start 0.67945 -0.3048)
			(end 0.67945 0.3048)
			(stroke
				(width 0.1)
				(type default)
			)
			(layer "F.Fab")
		)
		(fp_line
			(start -0.67945 -0.305054)
			(end -0.12065 -0.305054)
			(stroke
				(width 0.1)
				(type default)
			)
			(layer "F.Fab")
		)
		(fp_line
			(start -0.12065 -0.305054)
			(end -0.12065 -0.2794)
			(stroke
				(width 0.1)
				(type default)
			)
			(layer "F.Fab")
		)
		(pad "1" smd circle
			(at -0.40005 0 270)
			(size 0 0)
			(layers "F.Cu" "F.Mask" "F.Paste")
			(net "P3V3_AUX")
		)
		(pad "2" smd circle
			(at 0.40005 0 270)
			(size 0 0)
			(layers "F.Cu" "F.Mask" "F.Paste")
			(net "GND")
		)
	)
	(footprint ""
		(layer "F.Cu")
		(at 365.2012 -414.7566)
		(property "Reference" "C2391"
			(at 0 0 0)
			(layer "F.SilkS")
			(hide yes)
			(effects
				(font
					(size 1.27 1.27)
				)
			)
		)
		(property "Value" ""
			(at 0 0 0)
			(layer "F.Fab")
			(effects
				(font
					(size 1.27 1.27)
				)
			)
		)
		(duplicate_pad_numbers_are_jumpers no)
		(fp_line
			(start -0.7874 -0.4064)
			(end 0.7874 -0.4064)
			(stroke
				(width 0.1524)
				(type default)
			)
			(layer "F.SilkS")
		)
		(fp_line
			(start -0.7874 0.4064)
			(end -0.7874 -0.4064)
			(stroke
				(width 0.1524)
				(type default)
			)
			(layer "F.SilkS")
		)
		(fp_line
			(start 0.7874 -0.4064)
			(end 0.7874 0.4064)
			(stroke
				(width 0.1524)
				(type default)
			)
			(layer "F.SilkS")
		)
		(fp_line
			(start 0.7874 0.4064)
			(end -0.7874 0.4064)
			(stroke
				(width 0.1524)
				(type default)
			)
			(layer "F.SilkS")
		)
		(fp_line
			(start -0.67945 -0.305054)
			(end -0.12065 -0.305054)
			(stroke
				(width 0.1)
				(type default)
			)
			(layer "F.Fab")
		)
		(fp_line
			(start -0.67945 0.3048)
			(end -0.67945 -0.305054)
			(stroke
				(width 0.1)
				(type default)
			)
			(layer "F.Fab")
		)
		(fp_line
			(start -0.12065 -0.305054)
			(end -0.12065 -0.2794)
			(stroke
				(width 0.1)
				(type default)
			)
			(layer "F.Fab")
		)
		(fp_line
			(start -0.12065 -0.2794)
			(end 0.12065 -0.2794)
			(stroke
				(width 0.1)
				(type default)
			)
			(layer "F.Fab")
		)
		(fp_line
			(start -0.12065 0.2794)
			(end -0.12065 0.3048)
			(stroke
				(width 0.1)
				(type default)
			)
			(layer "F.Fab")
		)
		(fp_line
			(start -0.12065 0.3048)
			(end -0.67945 0.3048)
			(stroke
				(width 0.1)
				(type default)
			)
			(layer "F.Fab")
		)
		(fp_line
			(start 0.120396 0.2794)
			(end -0.12065 0.2794)
			(stroke
				(width 0.1)
				(type default)
			)
			(layer "F.Fab")
		)
		(fp_line
			(start 0.120396 0.3048)
			(end 0.120396 0.2794)
			(stroke
				(width 0.1)
				(type default)
			)
			(layer "F.Fab")
		)
		(fp_line
			(start 0.12065 -0.3048)
			(end 0.67945 -0.3048)
			(stroke
				(width 0.1)
				(type default)
			)
			(layer "F.Fab")
		)
		(fp_line
			(start 0.12065 -0.2794)
			(end 0.12065 -0.3048)
			(stroke
				(width 0.1)
				(type default)
			)
			(layer "F.Fab")
		)
		(fp_line
			(start 0.67945 -0.3048)
			(end 0.67945 0.3048)
			(stroke
				(width 0.1)
				(type default)
			)
			(layer "F.Fab")
		)
		(fp_line
			(start 0.67945 0.3048)
			(end 0.120396 0.3048)
			(stroke
				(width 0.1)
				(type default)
			)
			(layer "F.Fab")
		)
		(pad "1" smd circle
			(at -0.40005 0)
			(size 0 0)
			(layers "F.Cu" "F.Mask" "F.Paste")
			(net "PRSNT_CABLE_GPU_A3_ISO_N")
		)
		(pad "2" smd circle
			(at 0.40005 0)
			(size 0 0)
			(layers "F.Cu" "F.Mask" "F.Paste")
			(net "GND")
		)
	)
	(footprint ""
		(layer "F.Cu")
		(at 15.436596 -389.151876 180)
		(property "Reference" "R3290"
			(at 0 0 180)
			(layer "F.SilkS")
			(hide yes)
			(effects
				(font
					(size 1.27 1.27)
				)
			)
		)
		(property "Value" ""
			(at 0 0 180)
			(layer "F.Fab")
			(effects
				(font
					(size 1.27 1.27)
				)
			)
		)
		(duplicate_pad_numbers_are_jumpers no)
		(fp_line
			(start 0.7874 0.4064)
			(end -0.7874 0.4064)
			(stroke
				(width 0.1524)
				(type default)
			)
			(layer "F.SilkS")
		)
		(fp_line
			(start 0.7874 -0.4064)
			(end 0.7874 0.4064)
			(stroke
				(width 0.1524)
				(type default)
			)
			(layer "F.SilkS")
		)
		(fp_line
			(start -0.7874 0.4064)
			(end -0.7874 -0.4064)
			(stroke
				(width 0.1524)
				(type default)
			)
			(layer "F.SilkS")
		)
		(fp_line
			(start -0.7874 -0.4064)
			(end 0.7874 -0.4064)
			(stroke
				(width 0.1524)
				(type default)
			)
			(layer "F.SilkS")
		)
		(fp_line
			(start 0.67945 0.3048)
			(end 0.120396 0.3048)
			(stroke
				(width 0.1)
				(type default)
			)
			(layer "F.Fab")
		)
		(fp_line
			(start 0.67945 -0.3048)
			(end 0.67945 0.3048)
			(stroke
				(width 0.1)
				(type default)
			)
			(layer "F.Fab")
		)
		(fp_line
			(start 0.12065 -0.2794)
			(end 0.12065 -0.3048)
			(stroke
				(width 0.1)
				(type default)
			)
			(layer "F.Fab")
		)
		(fp_line
			(start 0.12065 -0.3048)
			(end 0.67945 -0.3048)
			(stroke
				(width 0.1)
				(type default)
			)
			(layer "F.Fab")
		)
		(fp_line
			(start 0.120396 0.3048)
			(end 0.120396 0.2794)
			(stroke
				(width 0.1)
				(type default)
			)
			(layer "F.Fab")
		)
		(fp_line
			(start 0.120396 0.2794)
			(end -0.12065 0.2794)
			(stroke
				(width 0.1)
				(type default)
			)
			(layer "F.Fab")
		)
		(fp_line
			(start -0.12065 0.3048)
			(end -0.67945 0.3048)
			(stroke
				(width 0.1)
				(type default)
			)
			(layer "F.Fab")
		)
		(fp_line
			(start -0.12065 0.2794)
			(end -0.12065 0.3048)
			(stroke
				(width 0.1)
				(type default)
			)
			(layer "F.Fab")
		)
		(fp_line
			(start -0.12065 -0.2794)
			(end 0.12065 -0.2794)
			(stroke
				(width 0.1)
				(type default)
			)
			(layer "F.Fab")
		)
		(fp_line
			(start -0.12065 -0.305054)
			(end -0.12065 -0.2794)
			(stroke
				(width 0.1)
				(type default)
			)
			(layer "F.Fab")
		)
		(fp_line
			(start -0.67945 0.3048)
			(end -0.67945 -0.305054)
			(stroke
				(width 0.1)
				(type default)
			)
			(layer "F.Fab")
		)
		(fp_line
			(start -0.67945 -0.305054)
			(end -0.12065 -0.305054)
			(stroke
				(width 0.1)
				(type default)
			)
			(layer "F.Fab")
		)
		(pad "1" smd circle
			(at -0.40005 0 180)
			(size 0 0)
			(layers "F.Cu" "F.Mask" "F.Paste")
			(net "FM_P2E_SWA")
		)
		(pad "2" smd circle
			(at 0.40005 0 180)
			(size 0 0)
			(layers "F.Cu" "F.Mask" "F.Paste")
			(net "GND")
		)
	)
	(footprint ""
		(layer "F.Cu")
		(at 62.35446 -156.47797)
		(property "Reference" "PL21"
			(at -3.47726 -4.491228 0)
			(unlocked yes)
			(layer "F.SilkS")
			(effects
				(font
					(size 0.7874 0.5842)
					(thickness 0.1524)
				)
				(justify left)
			)
		)
		(property "Value" ""
			(at 0 0 0)
			(layer "F.Fab")
			(effects
				(font
					(size 1.27 1.27)
				)
			)
		)
		(duplicate_pad_numbers_are_jumpers no)
		(fp_line
			(start -3.24993 -3.24993)
			(end 3.24993 -3.24993)
			(stroke
				(width 0.1524)
				(type default)
			)
			(layer "F.SilkS")
		)
		(fp_line
			(start -3.24993 -2.2352)
			(end -3.24993 -3.24993)
			(stroke
				(width 0.1524)
				(type default)
			)
			(layer "F.SilkS")
		)
		(fp_line
			(start -3.24993 3.24993)
			(end -3.24993 2.2352)
			(stroke
				(width 0.1524)
				(type default)
			)
			(layer "F.SilkS")
		)
		(fp_line
			(start 3.24993 -3.24993)
			(end 3.24993 -2.2352)
			(stroke
				(width 0.1524)
				(type default)
			)
			(layer "F.SilkS")
		)
		(fp_line
			(start 3.24993 2.2352)
			(end 3.24993 3.24993)
			(stroke
				(width 0.1524)
				(type default)
			)
			(layer "F.SilkS")
		)
		(fp_line
			(start 3.24993 3.24993)
			(end -3.24993 3.24993)
			(stroke
				(width 0.1524)
				(type default)
			)
			(layer "F.SilkS")
		)
		(fp_line
			(start -3.24993 -3.24993)
			(end 3.24993 -3.24993)
			(stroke
				(width 0.1)
				(type default)
			)
			(layer "F.Fab")
		)
		(fp_line
			(start -3.24993 3.24993)
			(end -3.24993 -3.24993)
			(stroke
				(width 0.1)
				(type default)
			)
			(layer "F.Fab")
		)
		(fp_line
			(start 3.24993 -3.24993)
			(end 3.24993 3.24993)
			(stroke
				(width 0.1)
				(type default)
			)
			(layer "F.Fab")
		)
		(fp_line
			(start 3.24993 3.24993)
			(end -3.24993 3.24993)
			(stroke
				(width 0.1)
				(type default)
			)
			(layer "F.Fab")
		)
		(pad "1" smd rect
			(at -2.29997 0)
			(size 2.0066 4.2164)
			(layers "F.Cu" "F.Mask" "F.Paste")
			(net "SW_PVCCINFAON_CPU1_SW1")
		)
		(pad "2" smd rect
			(at 2.29997 0)
			(size 2.0066 4.2164)
			(layers "F.Cu" "F.Mask" "F.Paste")
			(net "PVCCINFAON_CPU1")
		)
	)
)
